# T6G (Grand Teton) — schematic netlist excerpt (pin names and nets, part order shuffled) for the footprints in the layout excerpt that follows; sources: Cadence DE-HDL packaged netlist, KiCad conversion of 04192023_DAF0TMB3IC0_F0TG_MB_C_brd_V02_OCP.brd

PR403  Q_RES  1K 1% CHIP  pkg 0402LF  page 226 : A = PVDD18_S5_P1 ; B = GND
PR416  Q_RES  2.2 1% CHIP  pkg 0402LF  page 203 : A = PVDDCR_CPU1_P0_PVCC ; B = PVDDCR_CPU1_P0_VCC6
C985  Q_CAP  0.1UF 10V 10% X7S  pkg C0201  page 301 : A = P0V9_CPU0_RT2_2A ; B = GND

(kicad_pcb
	(version 20260206)
	(generator "pcbnew")
	(generator_version "10.0")
	(general
		(thickness 1.6)
		(legacy_teardrops no)
	)
	(paper "A4")
	(title_block
		(title "04192023_DAF0TMB3IC0_F0TG_MB_C_brd_V02_OCP.brd")
		(comment 1 "Grand Teton / footprints 7236-7238 of 8354")
	)
	(layers
		(0 "F.Cu" signal "TOP")
		(4 "In1.Cu" signal "GND")
		(6 "In2.Cu" signal "IN1")
		(8 "In3.Cu" signal "GND1")
		(10 "In4.Cu" signal "IN2")
		(12 "In5.Cu" signal "GND2")
		(14 "In6.Cu" signal "IN3")
		(16 "In7.Cu" signal "GND3")
		(18 "In8.Cu" signal "VCC")
		(20 "In9.Cu" signal "VCC1")
		(22 "In10.Cu" signal "GND4")
		(24 "In11.Cu" signal "IN4")
		(26 "In12.Cu" signal "GND5")
		(28 "In13.Cu" signal "IN5")
		(30 "In14.Cu" signal "GND6")
		(32 "In15.Cu" signal "IN6")
		(34 "In16.Cu" signal "GND7")
		(2 "B.Cu" signal "BOTTOM")
		(9 "F.Adhes" user "F.Adhesive")
		(11 "B.Adhes" user "B.Adhesive")
		(13 "F.Paste" user "Package Geometry/Pastemask Top")
		(15 "B.Paste" user "Package Geometry/Pastemask Bottom")
		(5 "F.SilkS" user "Ref Des/Silkscreen Top")
		(7 "B.SilkS" user "Ref Des/Silkscreen Bottom")
		(1 "F.Mask" user "Board Geometry/Soldermask Top")
		(3 "B.Mask" user "Board Geometry/Soldermask Bottom")
		(17 "Dwgs.User" user "User.Drawings")
		(19 "Cmts.User" user "User.Comments")
		(21 "Eco1.User" user "User.Eco1")
		(23 "Eco2.User" user "User.Eco2")
		(25 "Edge.Cuts" user "Board Geometry/Outline")
		(27 "Margin" user)
		(31 "F.CrtYd" user "Package Geometry/Place Bound Top")
		(29 "B.CrtYd" user "Package Geometry/Place Bound Bottom")
		(35 "F.Fab" user "Ref Des/Assembly Top")
		(33 "B.Fab" user "Ref Des/Assembly Bottom")
	)
	(footprint ""
		(layer "B.Cu")
		(at 58.580782 -148.322792 180)
		(property "Reference" "PR403"
			(at 0 0 0)
			(layer "B.SilkS")
			(hide yes)
			(effects
				(font
					(size 1.27 1.27)
				)
				(justify mirror)
			)
		)
		(property "Value" ""
			(at 0 0 0)
			(layer "B.Fab")
			(effects
				(font
					(size 1.27 1.27)
				)
				(justify mirror)
			)
		)
		(duplicate_pad_numbers_are_jumpers no)
		(fp_line
			(start 0.7874 0.4064)
			(end 0.7874 -0.4064)
			(stroke
				(width 0.1524)
				(type default)
			)
			(layer "B.SilkS")
		)
		(fp_line
			(start 0.7874 -0.4064)
			(end -0.7874 -0.4064)
			(stroke
				(width 0.1524)
				(type default)
			)
			(layer "B.SilkS")
		)
		(fp_line
			(start -0.7874 0.4064)
			(end 0.7874 0.4064)
			(stroke
				(width 0.1524)
				(type default)
			)
			(layer "B.SilkS")
		)
		(fp_line
			(start -0.7874 -0.4064)
			(end -0.7874 0.4064)
			(stroke
				(width 0.1524)
				(type default)
			)
			(layer "B.SilkS")
		)
		(fp_line
			(start 0.67945 0.3048)
			(end 0.67945 -0.305054)
			(stroke
				(width 0.1)
				(type default)
			)
			(layer "B.Fab")
		)
		(fp_line
			(start 0.67945 -0.305054)
			(end 0.12065 -0.305054)
			(stroke
				(width 0.1)
				(type default)
			)
			(layer "B.Fab")
		)
		(fp_line
			(start 0.12065 0.3048)
			(end 0.67945 0.3048)
			(stroke
				(width 0.1)
				(type default)
			)
			(layer "B.Fab")
		)
		(fp_line
			(start 0.12065 0.2794)
			(end 0.12065 0.3048)
			(stroke
				(width 0.1)
				(type default)
			)
			(layer "B.Fab")
		)
		(fp_line
			(start 0.12065 -0.2794)
			(end -0.12065 -0.2794)
			(stroke
				(width 0.1)
				(type default)
			)
			(layer "B.Fab")
		)
		(fp_line
			(start 0.12065 -0.305054)
			(end 0.12065 -0.2794)
			(stroke
				(width 0.1)
				(type default)
			)
			(layer "B.Fab")
		)
		(fp_line
			(start -0.120396 0.3048)
			(end -0.120396 0.2794)
			(stroke
				(width 0.1)
				(type default)
			)
			(layer "B.Fab")
		)
		(fp_line
			(start -0.120396 0.2794)
			(end 0.12065 0.2794)
			(stroke
				(width 0.1)
				(type default)
			)
			(layer "B.Fab")
		)
		(fp_line
			(start -0.12065 -0.2794)
			(end -0.12065 -0.3048)
			(stroke
				(width 0.1)
				(type default)
			)
			(layer "B.Fab")
		)
		(fp_line
			(start -0.12065 -0.3048)
			(end -0.67945 -0.3048)
			(stroke
				(width 0.1)
				(type default)
			)
			(layer "B.Fab")
		)
		(fp_line
			(start -0.67945 0.3048)
			(end -0.120396 0.3048)
			(stroke
				(width 0.1)
				(type default)
			)
			(layer "B.Fab")
		)
		(fp_line
			(start -0.67945 -0.3048)
			(end -0.67945 0.3048)
			(stroke
				(width 0.1)
				(type default)
			)
			(layer "B.Fab")
		)
		(pad "1" smd circle
			(at 0.40005 0)
			(size 0 0)
			(layers "B.Cu" "B.Mask" "B.Paste")
			(net "PVDD18_S5_P1")
		)
		(pad "2" smd circle
			(at -0.40005 0)
			(size 0 0)
			(layers "B.Cu" "B.Mask" "B.Paste")
			(net "GND")
		)
	)
	(footprint ""
		(layer "B.Cu")
		(at 349.355156 -340.99373 -90)
		(property "Reference" "PR416"
			(at 0 0 90)
			(layer "B.SilkS")
			(hide yes)
			(effects
				(font
					(size 1.27 1.27)
				)
				(justify mirror)
			)
		)
		(property "Value" ""
			(at 0 0 90)
			(layer "B.Fab")
			(effects
				(font
					(size 1.27 1.27)
				)
				(justify mirror)
			)
		)
		(duplicate_pad_numbers_are_jumpers no)
		(fp_line
			(start -0.7874 0.4064)
			(end 0.7874 0.4064)
			(stroke
				(width 0.1524)
				(type default)
			)
			(layer "B.SilkS")
		)
		(fp_line
			(start 0.7874 0.4064)
			(end 0.7874 -0.4064)
			(stroke
				(width 0.1524)
				(type default)
			)
			(layer "B.SilkS")
		)
		(fp_line
			(start -0.7874 -0.4064)
			(end -0.7874 0.4064)
			(stroke
				(width 0.1524)
				(type default)
			)
			(layer "B.SilkS")
		)
		(fp_line
			(start 0.7874 -0.4064)
			(end -0.7874 -0.4064)
			(stroke
				(width 0.1524)
				(type default)
			)
			(layer "B.SilkS")
		)
		(fp_line
			(start -0.67945 0.3048)
			(end -0.120396 0.3048)
			(stroke
				(width 0.1)
				(type default)
			)
			(layer "B.Fab")
		)
		(fp_line
			(start -0.120396 0.3048)
			(end -0.120396 0.2794)
			(stroke
				(width 0.1)
				(type default)
			)
			(layer "B.Fab")
		)
		(fp_line
			(start 0.12065 0.3048)
			(end 0.67945 0.3048)
			(stroke
				(width 0.1)
				(type default)
			)
			(layer "B.Fab")
		)
		(fp_line
			(start 0.67945 0.3048)
			(end 0.67945 -0.305054)
			(stroke
				(width 0.1)
				(type default)
			)
			(layer "B.Fab")
		)
		(fp_line
			(start -0.120396 0.2794)
			(end 0.12065 0.2794)
			(stroke
				(width 0.1)
				(type default)
			)
			(layer "B.Fab")
		)
		(fp_line
			(start 0.12065 0.2794)
			(end 0.12065 0.3048)
			(stroke
				(width 0.1)
				(type default)
			)
			(layer "B.Fab")
		)
		(fp_line
			(start -0.12065 -0.2794)
			(end -0.12065 -0.3048)
			(stroke
				(width 0.1)
				(type default)
			)
			(layer "B.Fab")
		)
		(fp_line
			(start 0.12065 -0.2794)
			(end -0.12065 -0.2794)
			(stroke
				(width 0.1)
				(type default)
			)
			(layer "B.Fab")
		)
		(fp_line
			(start -0.67945 -0.3048)
			(end -0.67945 0.3048)
			(stroke
				(width 0.1)
				(type default)
			)
			(layer "B.Fab")
		)
		(fp_line
			(start -0.12065 -0.3048)
			(end -0.67945 -0.3048)
			(stroke
				(width 0.1)
				(type default)
			)
			(layer "B.Fab")
		)
		(fp_line
			(start 0.12065 -0.305054)
			(end 0.12065 -0.2794)
			(stroke
				(width 0.1)
				(type default)
			)
			(layer "B.Fab")
		)
		(fp_line
			(start 0.67945 -0.305054)
			(end 0.12065 -0.305054)
			(stroke
				(width 0.1)
				(type default)
			)
			(layer "B.Fab")
		)
		(pad "1" smd circle
			(at 0.40005 0 90)
			(size 0 0)
			(layers "B.Cu" "B.Mask" "B.Paste")
			(net "PVDDCR_CPU1_P0_PVCC")
		)
		(pad "2" smd circle
			(at -0.40005 0 90)
			(size 0 0)
			(layers "B.Cu" "B.Mask" "B.Paste")
			(net "PVDDCR_CPU1_P0_VCC6")
		)
	)
	(footprint ""
		(layer "B.Cu")
		(at 406.746202 -396.393162 -90)
		(property "Reference" "C985"
			(at 0 0 90)
			(layer "B.SilkS")
			(hide yes)
			(effects
				(font
					(size 1.27 1.27)
				)
				(justify mirror)
			)
		)
		(property "Value" ""
			(at 0 0 90)
			(layer "B.Fab")
			(effects
				(font
					(size 1.27 1.27)
				)
				(justify mirror)
			)
		)
		(duplicate_pad_numbers_are_jumpers no)
		(fp_line
			(start -0.299974 0.150114)
			(end 0.299974 0.150114)
			(stroke
				(width 0.1)
				(type default)
			)
			(layer "B.Fab")
		)
		(fp_line
			(start 0.299974 0.150114)
			(end 0.299974 -0.150114)
			(stroke
				(width 0.1)
				(type default)
			)
			(layer "B.Fab")
		)
		(fp_line
			(start -0.299974 -0.150114)
			(end -0.299974 0.150114)
			(stroke
				(width 0.1)
				(type default)
			)
			(layer "B.Fab")
		)
		(fp_line
			(start 0.299974 -0.150114)
			(end -0.299974 -0.150114)
			(stroke
				(width 0.1)
				(type default)
			)
			(layer "B.Fab")
		)
		(pad "1" smd rect
			(at 0.2667 0 90)
			(size 0.3048 0.381)
			(layers "B.Cu" "B.Mask" "B.Paste")
			(net "P0V9_CPU0_RT2_2A")
		)
		(pad "2" smd rect
			(at -0.2667 0 90)
			(size 0.3048 0.381)
			(layers "B.Cu" "B.Mask" "B.Paste")
			(net "GND")
		)
	)
)
